#ISCELL
  mstr_misc dns *
  *
#ISCELL
  mstr_symbols cad_note *
  *
#ISCELL
  mstr_symbols intel_corp_bpage *
  *
#CELL
  mstr_discrete res *
  page145_i10
#CELL
  mstr_discrete res *
  page145_i100
#CELL
  mstr_discrete res *
  page145_i101
#ISCELL
  mstr_symbols gnd *
  page145_i102
#ISCELL
  mstr_standard offpage *
  page145_i103
#ISCELL
  mstr_standard offpage *
  page145_i104
#ISCELL
  mstr_standard offpage *
  page145_i109
#CELL
  mstr_discrete res *
  page145_i11
#ISCELL
  mstr_standard offpage *
  page145_i110
#ISCELL
  mstr_standard offpage *
  page145_i111
#ISCELL
  mstr_standard offpage *
  page145_i112
#ISCELL
  mstr_standard offpage *
  page145_i115
#ISCELL
  mstr_standard offpage *
  page145_i116
#CELL
  w_hdl ast2520a1-gp-gp *
  page145_i117
#ISCELL
  mstr_standard offpage *
  page145_i12
#ISCELL
  mstr_symbols gnd *
  page145_i13
#CELL
  mstr_discrete res *
  page145_i14
#CELL
  dev_discrete cap_a *
  page145_i15
#ISCELL
  mstr_symbols p3v3_stby *
  page145_i16
#ISCELL
  mstr_symbols gnd *
  page145_i17
#ISCELL
  mstr_standard offpage *
  page145_i18
#ISCELL
  mstr_standard offpage *
  page145_i19
#CELL
  mstr_discrete res *
  page145_i20
#ISCELL
  mstr_standard offpage *
  page145_i21
#CELL
  mstr_discrete res *
  page145_i22
#ISCELL
  mstr_symbols gnd *
  page145_i23
#ISCELL
  mstr_standard offpage *
  page145_i24
#ISCELL
  mstr_standard offpage *
  page145_i25
#ISCELL
  mstr_standard offpage *
  page145_i26
#ISCELL
  mstr_standard offpage *
  page145_i27
#ISCELL
  mstr_standard offpage *
  page145_i28
#ISCELL
  mstr_standard offpage *
  page145_i29
#CELL
  mstr_discrete res *
  page145_i30
#CELL
  mstr_discrete res *
  page145_i31
#ISCELL
  mstr_symbols gnd *
  page145_i32
#ISCELL
  mstr_symbols gnd *
  page145_i33
#CELL
  mstr_discrete res *
  page145_i34
#ISCELL
  mstr_symbols gnd *
  page145_i35
#CELL
  mstr_discrete res *
  page145_i36
#ISCELL
  mstr_symbols gnd *
  page145_i37
#CELL
  mstr_discrete res *
  page145_i38
#ISCELL
  mstr_symbols gnd *
  page145_i39
#ISCELL
  mstr_standard offpage *
  page145_i4
#ISCELL
  mstr_standard offpage *
  page145_i41
#ISCELL
  mstr_standard offpage *
  page145_i42
#ISCELL
  mstr_standard offpage *
  page145_i43
#CELL
  dev_discrete cap_a *
  page145_i44
#CELL
  dev_discrete cap_a *
  page145_i45
#CELL
  mstr_discrete res *
  page145_i46
#ISCELL
  mstr_symbols gnd *
  page145_i47
#ISCELL
  mstr_standard offpage *
  page145_i48
#ISCELL
  mstr_standard offpage *
  page145_i49
#ISCELL
  mstr_standard offpage *
  page145_i5
#ISCELL
  mstr_standard offpage *
  page145_i51
#ISCELL
  mstr_standard offpage *
  page145_i52
#ISCELL
  mstr_standard offpage *
  page145_i53
#ISCELL
  mstr_standard offpage *
  page145_i54
#ISCELL
  mstr_standard offpage *
  page145_i55
#ISCELL
  mstr_standard offpage *
  page145_i56
#ISCELL
  mstr_standard offpage *
  page145_i57
#ISCELL
  mstr_standard offpage *
  page145_i58
#ISCELL
  mstr_standard offpage *
  page145_i59
#ISCELL
  mstr_standard offpage *
  page145_i6
#ISCELL
  mstr_standard offpage *
  page145_i68
#ISCELL
  mstr_standard offpage *
  page145_i69
#ISCELL
  mstr_standard offpage *
  page145_i7
#ISCELL
  mstr_standard offpage *
  page145_i70
#ISCELL
  mstr_standard offpage *
  page145_i71
#ISCELL
  mstr_standard offpage *
  page145_i72
#ISCELL
  mstr_standard offpage *
  page145_i73
#ISCELL
  mstr_standard offpage *
  page145_i74
#ISCELL
  mstr_standard offpage *
  page145_i75
#ISCELL
  mstr_standard offpage *
  page145_i76
#ISCELL
  mstr_standard offpage *
  page145_i78
#ISCELL
  mstr_standard offpage *
  page145_i79
#CELL
  mstr_discrete osc_c *
  page145_i8
#ISCELL
  mstr_standard offpage *
  page145_i80
#ISCELL
  mstr_standard offpage *
  page145_i81
#ISCELL
  mstr_standard offpage *
  page145_i82
#ISCELL
  mstr_standard offpage *
  page145_i83
#ISCELL
  mstr_standard offpage *
  page145_i84
#ISCELL
  mstr_standard offpage *
  page145_i85
#ISCELL
  mstr_standard offpage *
  page145_i86
#ISCELL
  mstr_standard offpage *
  page145_i87
#ISCELL
  mstr_standard offpage *
  page145_i88
#ISCELL
  mstr_standard offpage *
  page145_i89
#ISCELL
  mstr_standard offpage *
  page145_i9
#ISCELL
  mstr_standard offpage *
  page145_i90
#ISCELL
  mstr_standard offpage *
  page145_i91
#ISCELL
  mstr_standard offpage *
  page145_i92
#ISCELL
  mstr_standard offpage *
  page145_i93
#ISCELL
  mstr_standard offpage *
  page145_i94
#ISCELL
  mstr_standard offpage *
  page145_i95
#ISCELL
  mstr_standard offpage *
  page145_i96
#ISCELL
  mstr_standard offpage *
  page145_i97
#ISCELL
  mstr_standard offpage *
  page145_i98
#ISCELL
  mstr_standard offpage *
  page145_i99
